("..\\packaged\\pstdmlmodels.dat" 
 (PackagedDevice 
  ("DEFAULT_RESISTOR_0.001OHM_2_1" 
   (ESpice ".subckt DEFAULT_RESISTOR_0.001OHM_2_1 1 2
R1 1 2 0.001
.ends DEFAULT_RESISTOR_0.001OHM_2_1
" ) 
   (PinConnections 
    (1 2 ) 
    (2 1 ) ) ) 
  (DEFAULT_CAPACITOR_100000pF_2_1 
   (ESpice ".subckt DEFAULT_CAPACITOR_100000pF_2_1 1 2
C1 1 2 1e-007
.ends DEFAULT_CAPACITOR_100000pF_2_1
" ) 
   (PinConnections 
    (1 2 ) 
    (2 1 ) ) ) 
  (DEFAULT_CAPACITOR_10000pF_2_1 
   (ESpice ".subckt DEFAULT_CAPACITOR_10000pF_2_1 1 2
C1 1 2 1e-008
.ends DEFAULT_CAPACITOR_10000pF_2_1
" ) 
   (PinConnections 
    (1 2 ) 
    (2 1 ) ) ) 
  (DEFAULT_RESISTOR_332OHM_2_1 
   (ESpice ".subckt DEFAULT_RESISTOR_332OHM_2_1 1 2
R1 1 2 332
.ends DEFAULT_RESISTOR_332OHM_2_1
" ) 
   (PinConnections 
    (1 2 ) 
    (2 1 ) ) ) 
  (DEFAULT_RESISTOR_47000OHM_2_1 
   (ESpice ".subckt DEFAULT_RESISTOR_47000OHM_2_1 1 2
R1 1 2 47000
.ends DEFAULT_RESISTOR_47000OHM_2_1
" ) 
   (PinConnections 
    (1 2 ) 
    (2 1 ) ) ) 
  (DEFAULT_RESISTOR_4750OHM_2_1 
   (ESpice ".subckt DEFAULT_RESISTOR_4750OHM_2_1 1 2
R1 1 2 4750
.ends DEFAULT_RESISTOR_4750OHM_2_1
" ) 
   (PinConnections 
    (1 2 ) 
    (2 1 ) ) ) 
  (DEFAULT_RESISTOR_750OHM_2_1 
   (ESpice ".subckt DEFAULT_RESISTOR_750OHM_2_1 1 2
R1 1 2 750
.ends DEFAULT_RESISTOR_750OHM_2_1
" ) 
   (PinConnections 
    (1 2 ) 
    (2 1 ) ) ) ) 
 (LibraryVersion 136.2 ) ) 